# S9S_MB_2U (Grand Teton) — schematic parts with pin connectivity, parts 1611–1611 of 6093; source: Cadence DE-HDL packaged netlist (pstxprt.dat, pstxnet.dat, pstchip.dat)

J18  SCONN288_ADR50017P087CC  SCONN288_ADR50017-P087CC IO  pkg DDR288S_1-1VXB  page 99
  1  VIN_BULK0  POWER  = P12V_S3_AUX_CPU1_NVDIMM
  2  RFU0  TRI  = TP_CHA_CPU1_DIMM2_FRU_0
  3  VIN_MGMT  POWER  = P3V3_AUX
  4  HSCL  IN  = I3C_SPD_DDRABCD_CPU1_LVC1_SCL_1
  5  HSDA  BI  = I3C_SPD_DDRABCD_CPU1_LVC1_SDA
  6  VSS0  POWER  = GND
  7  DQ0_A  BI  = M_A_CPU1_SA_DQ<0>
  8  VSS1  POWER  = GND
  9  DQ1_A  BI  = M_A_CPU1_SA_DQ<1>
  10  VSS2  POWER  = GND
  11  DQS0_A_T  BI  = M_A_CPU1_SA_DQS_DP<0>
  12  DQS0_A_C  BI  = M_A_CPU1_SA_DQS_DN<0>
  13  VSS3  POWER  = GND
  14  DQ4_A  BI  = M_A_CPU1_SA_DQ<4>
  15  VSS4  POWER  = GND
  16  DQ5_A  BI  = M_A_CPU1_SA_DQ<5>
  17  VSS5  POWER  = GND
  18  DQ8_A  BI  = M_A_CPU1_SA_DQ<8>
  19  VSS6  POWER  = GND
  20  DQ9_A  BI  = M_A_CPU1_SA_DQ<9>
  21  VSS7  POWER  = GND
  22  DQS1_A_T  BI  = M_A_CPU1_SA_DQS_DP<1>
  23  DQS1_A_C  BI  = M_A_CPU1_SA_DQS_DN<1>
  24  VSS8  POWER  = GND
  25  DQ12_A  BI  = M_A_CPU1_SA_DQ<12>
  26  VSS9  POWER  = GND
  27  DQ13_A  BI  = M_A_CPU1_SA_DQ<13>
  28  VSS10  POWER  = GND
  29  DQ16_A  BI  = M_A_CPU1_SA_DQ<16>
  30  VSS11  POWER  = GND
  31  DQ17_A  BI  = M_A_CPU1_SA_DQ<17>
  32  VSS12  POWER  = GND
  33  DQS2_A_T  BI  = M_A_CPU1_SA_DQS_DP<2>
  34  DQS2_A_C  BI  = M_A_CPU1_SA_DQS_DN<2>
  35  VSS13  POWER  = GND
  36  DQ20_A  BI  = M_A_CPU1_SA_DQ<20>
  37  VSS14  POWER  = GND
  38  DQ21_A  BI  = M_A_CPU1_SA_DQ<21>
  39  VSS15  POWER  = GND
  40  DQ24_A  BI  = M_A_CPU1_SA_DQ<24>
  41  VSS16  POWER  = GND
  42  DQ25_A  BI  = M_A_CPU1_SA_DQ<25>
  43  VSS17  POWER  = GND
  44  DQS3_A_T  BI  = M_A_CPU1_SA_DQS_DP<3>
  45  DQS3_A_C  BI  = M_A_CPU1_SA_DQS_DN<3>
  46  VSS18  POWER  = GND
  47  DQ28_A  BI  = M_A_CPU1_SA_DQ<28>
  48  VSS19  POWER  = GND
  49  DQ29_A  BI  = M_A_CPU1_SA_DQ<29>
  50  VSS20  POWER  = GND
  51  CB0_A  BI  = M_A_CPU1_SA_CB<0>
  52  VSS21  POWER  = GND
  53  CB1_A  BI  = M_A_CPU1_SA_CB<1>
  54  VSS22  POWER  = GND
  55  DQS4_A_T  BI  = M_A_CPU1_SA_DQS_DP<4>
  56  DQS4_A_C  BI  = M_A_CPU1_SA_DQS_DN<4>
  57  VSS23  POWER  = GND
  58  CB4_A  BI  = M_A_CPU1_SA_CB<4>
  59  VSS24  POWER  = GND
  60  CB5_A  BI  = M_A_CPU1_SA_CB<5>
  61  VSS25  POWER  = GND
  62  ALERT_N  OUT  = M_A_CPU1_ALERT_N
  63  VSS26  POWER  = GND
  64  CS0_A_N  IN  = M_A_CPU1_SA_CS_N<2>
  65  VSS27  POWER  = GND
  66  CA0_A  IN  = M_A_CPU1_SA_CA<0>
  67  VSS28  POWER  = GND
  68  CA2_A  IN  = M_A_CPU1_SA_CA<2>
  69  VSS29  POWER  = GND
  70  CA4_A  IN  = M_A_CPU1_SA_CA<4>
  71  VSS30  POWER  = GND
  72  CA6_A  IN  = M_A_CPU1_SA_CA<6>
  73  VSS31  POWER  = GND
  74  PAR_A  IN  = M_A_CPU1_SA_PAR
  75  VSS32  POWER  = GND
  76  CA0_B  IN  = M_A_CPU1_SB_CA<0>
  77  VSS33  POWER  = GND
  78  CA2_B  IN  = M_A_CPU1_SB_CA<2>
  79  VSS34  POWER  = GND
  80  CA4_B  IN  = M_A_CPU1_SB_CA<4>
  81  VSS35  POWER  = GND
  82  CA6_B  IN  = M_A_CPU1_SB_CA<6>
  83  VSS36  POWER  = GND
  84  CS0_B_N  IN  = M_A_CPU1_SB_CS_N<2>
  85  VSS37  POWER  = GND
  86  \lbd||rsp_a_n\  OUT  = M_A_CPU1_SA_RSP<1>
  87  \lbs||rsp_b_n\  OUT  = M_A_CPU1_SB_RSP<1>
  88  VSS38  POWER  = GND
  89  CB4_B  BI  = M_A_CPU1_SB_CB<4>
  90  VSS39  POWER  = GND
  91  CB5_B  BI  = M_A_CPU1_SB_CB<5>
  92  VSS40  POWER  = GND
  93  \dqs9_b_t||tdqs9_b_t||dbi4_b_n\  BI  = M_A_CPU1_SB_DQS_DP<9>
  94  \dqs9_b_c||tdqs9_b_c\  BI  = M_A_CPU1_SB_DQS_DN<9>
  95  VSS41  POWER  = GND
  96  CB0_B  BI  = M_A_CPU1_SB_CB<0>
  97  VSS42  POWER  = GND
  98  CB1_B  BI  = M_A_CPU1_SB_CB<1>
  99  VSS43  POWER  = GND
  100  DQ0_B  BI  = M_A_CPU1_SB_DQ<0>
  101  VSS44  POWER  = GND
  102  DQ1_B  BI  = M_A_CPU1_SB_DQ<1>
  103  VSS45  POWER  = GND
  104  DQS0_B_T  BI  = M_A_CPU1_SB_DQS_DP<0>
  105  DQS0_B_C  BI  = M_A_CPU1_SB_DQS_DN<0>
  106  VSS46  POWER  = GND
  107  DQ4_B  BI  = M_A_CPU1_SB_DQ<4>
  108  VSS47  POWER  = GND
  109  DQ5_B  BI  = M_A_CPU1_SB_DQ<5>
  110  VSS48  POWER  = GND
  111  DQ8_B  BI  = M_A_CPU1_SB_DQ<8>
  112  VSS49  POWER  = GND
  113  DQ9_B  BI  = M_A_CPU1_SB_DQ<9>
  114  VSS50  POWER  = GND
  115  DQS1_B_T  BI  = M_A_CPU1_SB_DQS_DP<1>
  116  DQS1_B_C  BI  = M_A_CPU1_SB_DQS_DN<1>
  117  VSS51  POWER  = GND
  118  DQ12_B  BI  = M_A_CPU1_SB_DQ<12>
  119  VSS52  POWER  = GND
  120  DQ13_B  BI  = M_A_CPU1_SB_DQ<13>
  121  VSS53  POWER  = GND
  122  DQ16_B  BI  = M_A_CPU1_SB_DQ<16>
  123  VSS54  POWER  = GND
  124  DQ17_B  BI  = M_A_CPU1_SB_DQ<17>
  125  VSS55  POWER  = GND
  126  DQS2_B_T  BI  = M_A_CPU1_SB_DQS_DP<2>
  127  DQS2_B_C  BI  = M_A_CPU1_SB_DQS_DN<2>
  128  VSS56  POWER  = GND
  129  DQ20_B  BI  = M_A_CPU1_SB_DQ<20>
  130  VSS57  POWER  = GND
  131  DQ21_B  BI  = M_A_CPU1_SB_DQ<21>
  132  VSS58  POWER  = GND
  133  DQ24_B  BI  = M_A_CPU1_SB_DQ<24>
  134  VSS59  POWER  = GND
  135  DQ25_B  BI  = M_A_CPU1_SB_DQ<25>
  136  VSS60  POWER  = GND
  137  DQS3_B_T  BI  = M_A_CPU1_SB_DQS_DP<3>
  138  DQS3_B_C  BI  = M_A_CPU1_SB_DQS_DN<3>
  139  VSS61  POWER  = GND
  140  DQ28_B  BI  = M_A_CPU1_SB_DQ<28>
  141  VSS62  POWER  = GND
  142  DQ29_B  BI  = M_A_CPU1_SB_DQ<29>
  143  VSS63  POWER  = GND
  144  RFU1  TRI  = TP_CHA_CPU1_DIMM2_FRU_1
  145  VIN_BULK1  POWER  = P12V_S3_AUX_CPU1_NVDIMM
  146  VIN_BULK2  POWER  = P12V_S3_AUX_CPU1_NVDIMM
  147  \pwr_good||fail_n\  BI  = PWRGD_CHA_CPU1_DIMM2
  148  HSA  IN  = PD_CHA_CPU1_DIMM2_SAA
  149  RFU2  TRI  = TP_CHA_CPU1_DIMM2_FRU_2
  150  RFU3  TRI  = TP_CHA_CPU1_DIMM2_FRU_3
  151  VSS64  POWER  = GND
  152  DQ2_A  BI  = M_A_CPU1_SA_DQ<2>
  153  VSS65  POWER  = GND
  154  DQ3_A  BI  = M_A_CPU1_SA_DQ<3>
  155  VSS66  POWER  = GND
  156  \dqs5_a_c||tdqs5_a_c||dqs5_a_t||tdqs5_a_t\  BI  = M_A_CPU1_SA_DQS_DN<5>
  157  \dqs5_a_t||tdqs5_a_t\  BI  = M_A_CPU1_SA_DQS_DP<5>
  158  VSS67  POWER  = GND
  159  DQ6_A  BI  = M_A_CPU1_SA_DQ<6>
  160  VSS68  POWER  = GND
  161  DQ7_A  BI  = M_A_CPU1_SA_DQ<7>
  162  VSS69  POWER  = GND
  163  DQ10_A  BI  = M_A_CPU1_SA_DQ<10>
  164  VSS70  POWER  = GND
  165  DQ11_A  BI  = M_A_CPU1_SA_DQ<11>
  166  VSS71  POWER  = GND
  167  \dqs6_a_c||tdqs6_a_c||dqs6_a_t||tdqs6_a_t\  BI  = M_A_CPU1_SA_DQS_DN<6>
  168  \dqs6_a_t||tdqs6_a_t\  BI  = M_A_CPU1_SA_DQS_DP<6>
  169  VSS72  POWER  = GND
  170  DQ14_A  BI  = M_A_CPU1_SA_DQ<14>
  171  VSS73  POWER  = GND
  172  DQ15_A  BI  = M_A_CPU1_SA_DQ<15>
  173  VSS74  POWER  = GND
  174  DQ18_A  BI  = M_A_CPU1_SA_DQ<18>
  175  VSS75  POWER  = GND
  176  DQ19_A  BI  = M_A_CPU1_SA_DQ<19>
  177  VSS76  POWER  = GND
  178  \dqs7_a_c||tdqs7_a_c\  BI  = M_A_CPU1_SA_DQS_DN<7>
  179  \dqs7_a_t||tdqs7_a_t\  BI  = M_A_CPU1_SA_DQS_DP<7>
  180  VSS77  POWER  = GND
  181  DQ22_A  BI  = M_A_CPU1_SA_DQ<22>
  182  VSS78  POWER  = GND
  183  DQ23_A  BI  = M_A_CPU1_SA_DQ<23>
  184  VSS79  POWER  = GND
  185  DQ26_A  BI  = M_A_CPU1_SA_DQ<26>
  186  VSS80  POWER  = GND
  187  DQ27_A  BI  = M_A_CPU1_SA_DQ<27>
  188  VSS81  POWER  = GND
  189  \dqs8_a_c||tdqs8_a_c\  BI  = M_A_CPU1_SA_DQS_DN<8>
  190  \dqs8_a_t||tdqs8_a_t\  BI  = M_A_CPU1_SA_DQS_DP<8>
  191  VSS82  POWER  = GND
  192  DQ30_A  BI  = M_A_CPU1_SA_DQ<30>
  193  VSS83  POWER  = GND
  194  DQ31_A  BI  = M_A_CPU1_SA_DQ<31>
  195  VSS84  POWER  = GND
  196  CB2_A  BI  = M_A_CPU1_SA_CB<2>
  197  VSS85  POWER  = GND
  198  CB3_A  BI  = M_A_CPU1_SA_CB<3>
  199  VSS86  POWER  = GND
  200  \dqs9_a_c||tdqs9_a_c\  BI  = M_A_CPU1_SA_DQS_DN<9>
  201  \dqs9_a_t||tdqs9_a_t\  BI  = M_A_CPU1_SA_DQS_DP<9>
  202  VSS87  POWER  = GND
  203  CB6_A  BI  = M_A_CPU1_SA_CB<6>
  204  VSS88  POWER  = GND
  205  CB7_A  BI  = M_A_CPU1_SA_CB<7>
  206  VSS89  POWER  = GND
  207  RESET_N  IN  = RST_M_AB_CPU1_FPGA_N
  208  VSS90  POWER  = GND
  209  CS1_A_N  IN  = M_A_CPU1_SA_CS_N<3>
  210  VSS91  POWER  = GND
  211  CA1_A  IN  = M_A_CPU1_SA_CA<1>
  212  VSS92  POWER  = GND
  213  CA3_A  IN  = M_A_CPU1_SA_CA<3>
  214  VSS93  POWER  = GND
  215  CA5_A  IN  = M_A_CPU1_SA_CA<5>
  216  VSS94  POWER  = GND
  217  CK_T  IN  = M_A_CPU1_CLK_DP<1>
  218  CK_C  IN  = M_A_CPU1_CLK_DN<1>
  219  VSS95  POWER  = GND
  220  RFU4  TRI  = TP_CHA_CPU1_DIMM2_FRU_4
  221  CA1_B  IN  = M_A_CPU1_SB_CA<1>
  222  VSS96  POWER  = GND
  223  CA3_B  IN  = M_A_CPU1_SB_CA<3>
  224  VSS97  POWER  = GND
  225  CA5_B  IN  = M_A_CPU1_SB_CA<5>
  226  VSS98  POWER  = GND
  227  PAR_B  IN  = M_A_CPU1_SB_PAR
  228  VSS99  POWER  = GND
  229  CS1_B_N  IN  = M_A_CPU1_SB_CS_N<3>
  230  VSS100  POWER  = GND
  231  RFU5  TRI  = TP_CHA_CPU1_DIMM2_FRU_5
  232  RFU6  TRI  = TP_CHA_CPU1_DIMM2_FRU_6
  233  VSS101  POWER  = GND
  234  CB6_B  BI  = M_A_CPU1_SB_CB<6>
  235  VSS102  POWER  = GND
  236  CB7_B  BI  = M_A_CPU1_SB_CB<7>
  237  VSS103  POWER  = GND
  238  DQS4_B_C  BI  = M_A_CPU1_SB_DQS_DN<4>
  239  DQS4_B_T  BI  = M_A_CPU1_SB_DQS_DP<4>
  240  VSS104  POWER  = GND
  241  CB2_B  BI  = M_A_CPU1_SB_CB<2>
  242  VSS105  POWER  = GND
  243  CB3_B  BI  = M_A_CPU1_SB_CB<3>
  244  VSS106  POWER  = GND
  245  DQ2_B  BI  = M_A_CPU1_SB_DQ<2>
  246  VSS107  POWER  = GND
  247  DQ3_B  BI  = M_A_CPU1_SB_DQ<3>
  248  VSS108  POWER  = GND
  249  \dqs5_b_c||tdqs5_b_c\  BI  = M_A_CPU1_SB_DQS_DN<5>
  250  \dqs5_b_t||tdqs5_b_t\  BI  = M_A_CPU1_SB_DQS_DP<5>
  251  VSS109  POWER  = GND
  252  DQ6_B  BI  = M_A_CPU1_SB_DQ<6>
  253  VSS110  POWER  = GND
  254  DQ7_B  BI  = M_A_CPU1_SB_DQ<7>
  255  VSS111  POWER  = GND
  256  DQ10_B  BI  = M_A_CPU1_SB_DQ<10>
  257  VSS112  POWER  = GND
  258  DQ11_B  BI  = M_A_CPU1_SB_DQ<11>
  259  VSS113  POWER  = GND
  260  \dqs6_b_c||tdqs6_b_c\  BI  = M_A_CPU1_SB_DQS_DN<6>
  261  \dqs6_b_t||tdqs6_b_t\  BI  = M_A_CPU1_SB_DQS_DP<6>
  262  VSS114  POWER  = GND
  263  DQ14_B  BI  = M_A_CPU1_SB_DQ<14>
  264  VSS115  POWER  = GND
  265  DQ15_B  BI  = M_A_CPU1_SB_DQ<15>
  266  VSS116  POWER  = GND
  267  DQ18_B  BI  = M_A_CPU1_SB_DQ<18>
  268  VSS117  POWER  = GND
  269  DQ19_B  BI  = M_A_CPU1_SB_DQ<19>
  270  VSS118  POWER  = GND
  271  \dqs7_b_c||tdqs7_b_c\  BI  = M_A_CPU1_SB_DQS_DN<7>
  272  \dqs7_b_t||tdqs7_b_t\  BI  = M_A_CPU1_SB_DQS_DP<7>
  273  VSS119  POWER  = GND
  274  DQ22_B  BI  = M_A_CPU1_SB_DQ<22>
  275  VSS120  POWER  = GND
  276  DQ23_B  BI  = M_A_CPU1_SB_DQ<23>
  277  VSS121  POWER  = GND
  278  DQ26_B  BI  = M_A_CPU1_SB_DQ<26>
  279  VSS122  POWER  = GND
  280  DQ27_B  BI  = M_A_CPU1_SB_DQ<27>
  281  VSS123  POWER  = GND
  282  \dqs8_b_c||tdqs8_b_c\  BI  = M_A_CPU1_SB_DQS_DN<8>
  283  \dqs8_b_t||tdqs8_b_t\  BI  = M_A_CPU1_SB_DQS_DP<8>
  284  VSS124  POWER  = GND
  285  DQ30_B  BI  = M_A_CPU1_SB_DQ<30>
  286  VSS125  POWER  = GND
  287  DQ31_B  BI  = M_A_CPU1_SB_DQ<31>
  288  VSS126  POWER  = GND
  G1  G1  POWER  = GND
  G2  G2  POWER  = GND
  G3  G3  POWER  = GND
